(kicad_pcb
	(version 20260206)
	(generator "pcbnew")
	(generator_version "10.0")
	(general
		(thickness 1.6)
		(legacy_teardrops no)
	)
	(paper "A4")
	(title_block
		(title "Bryce Canyon_SCC_16316-1_OCP.brd")
		(comment 1 "Bryce Canyon / footprints 642-648 of 1561")
	)
	(layers
		(0 "F.Cu" signal "TOP")
		(4 "In1.Cu" signal "L2GND")
		(6 "In2.Cu" signal "L3")
		(8 "In3.Cu" signal "L4VCC")
		(10 "In4.Cu" signal "L5VCC")
		(12 "In5.Cu" signal "L6")
		(14 "In6.Cu" signal "L7GND")
		(2 "B.Cu" signal "BOTTOM")
		(9 "F.Adhes" user "F.Adhesive")
		(11 "B.Adhes" user "B.Adhesive")
		(13 "F.Paste" user "Package Geometry/Pastemask Top")
		(15 "B.Paste" user "Package Geometry/Pastemask Bottom")
		(5 "F.SilkS" user "Ref Des/Silkscreen Top")
		(7 "B.SilkS" user "Ref Des/Silkscreen Bottom")
		(1 "F.Mask" user "Board Geometry/Soldermask Top")
		(3 "B.Mask" user "Board Geometry/Soldermask Bottom")
		(17 "Dwgs.User" user "User.Drawings")
		(19 "Cmts.User" user "User.Comments")
		(21 "Eco1.User" user "User.Eco1")
		(23 "Eco2.User" user "User.Eco2")
		(25 "Edge.Cuts" user "Board Geometry/Outline")
		(27 "Margin" user)
		(31 "F.CrtYd" user "Package Geometry/Place Bound Top")
		(29 "B.CrtYd" user "Package Geometry/Place Bound Bottom")
		(35 "F.Fab" user "Ref Des/Assembly Top")
		(33 "B.Fab" user "Ref Des/Assembly Bottom")
	)
	(footprint ""
		(layer "F.Cu")
		(at 151.897842 -98.605594 180)
		(property "Reference" "C506"
			(at 0 0 180)
			(layer "F.SilkS")
			(hide yes)
			(effects
				(font
					(size 1.27 1.27)
				)
			)
		)
		(property "Value" "SCD1U16V2KX-3GP"
			(at 1.1811 -2.7051 180)
			(unlocked yes)
			(layer "F.Fab")
			(hide yes)
			(effects
				(font
					(size 1.016 1.016)
					(thickness 0.1524)
				)
			)
		)
		(property "Device Type" "C402H22"
			(at 1.1811 -4.2291 180)
			(unlocked yes)
			(layer "F.Fab")
			(hide yes)
			(effects
				(font
					(size 1.016 1.016)
					(thickness 0.1524)
				)
			)
		)
		(duplicate_pad_numbers_are_jumpers no)
		(fp_rect
			(start -0.4318 0.9525)
			(end 0.4318 -0.9525)
			(stroke
				(width 0)
				(type default)
			)
			(fill no)
			(layer "F.CrtYd")
		)
		(fp_rect
			(start -0.4318 0.9525)
			(end 0.4318 -0.9525)
			(stroke
				(width 0)
				(type default)
			)
			(fill no)
			(layer "F.Fab")
		)
		(pad "1" smd custom
			(at 0 -0.4445 180)
			(size 0.1524 0.1524)
			(layers "F.Cu" "F.Mask" "F.Paste")
			(net "P1V8_E")
			(options
				(clearance outline)
				(anchor circle)
			)
			(primitives
				(gr_poly
					(pts
						(arc
							(start 0.3048 -0.2032)
							(mid 0.275042 -0.275042)
							(end 0.2032 -0.3048)
						)
						(arc
							(start -0.2032 -0.3048)
							(mid -0.275042 -0.275042)
							(end -0.3048 -0.2032)
						)
						(arc
							(start -0.3048 0.2032)
							(mid -0.275042 0.275042)
							(end -0.2032 0.3048)
						)
						(arc
							(start 0.2032 0.3048)
							(mid 0.275042 0.275042)
							(end 0.3048 0.2032)
						)
					)
					(width 0)
					(fill yes)
				)
			)
		)
		(pad "2" smd custom
			(at 0 0.4445 180)
			(size 0.1524 0.1524)
			(layers "F.Cu" "F.Mask" "F.Paste")
			(net "GND")
			(options
				(clearance outline)
				(anchor circle)
			)
			(primitives
				(gr_poly
					(pts
						(arc
							(start 0.3048 -0.2032)
							(mid 0.275042 -0.275042)
							(end 0.2032 -0.3048)
						)
						(arc
							(start -0.2032 -0.3048)
							(mid -0.275042 -0.275042)
							(end -0.3048 -0.2032)
						)
						(arc
							(start -0.3048 0.2032)
							(mid -0.275042 0.275042)
							(end -0.2032 0.3048)
						)
						(arc
							(start 0.2032 0.3048)
							(mid 0.275042 0.275042)
							(end 0.3048 0.2032)
						)
					)
					(width 0)
					(fill yes)
				)
			)
		)
	)
	(footprint ""
		(layer "F.Cu")
		(at 11.045698 -43.314874 180)
		(property "Reference" "Q37"
			(at 0 0 180)
			(layer "F.SilkS")
			(hide yes)
			(effects
				(font
					(size 1.27 1.27)
				)
			)
		)
		(property "Value" "MMBT3904-3-GP"
			(at 0.10287 -10.29843 180)
			(unlocked yes)
			(layer "F.Fab")
			(hide yes)
			(effects
				(font
					(size 1.016 1.016)
					(thickness 0.1524)
				)
			)
		)
		(property "Device Type" "SOT23CBE2D4H44"
			(at 0.10287 -12.20343 180)
			(unlocked yes)
			(layer "F.Fab")
			(hide yes)
			(effects
				(font
					(size 1.016 1.016)
					(thickness 0.1524)
				)
			)
		)
		(duplicate_pad_numbers_are_jumpers no)
		(fp_line
			(start 1.651 1.778)
			(end 1.651 -1.778)
			(stroke
				(width 0.1524)
				(type default)
			)
			(layer "F.SilkS")
		)
		(fp_line
			(start 1.651 -1.778)
			(end -1.651 -1.778)
			(stroke
				(width 0.1524)
				(type default)
			)
			(layer "F.SilkS")
		)
		(fp_line
			(start -1.651 1.778)
			(end 1.651 1.778)
			(stroke
				(width 0.1524)
				(type default)
			)
			(layer "F.SilkS")
		)
		(fp_line
			(start -1.651 -1.778)
			(end -1.651 1.778)
			(stroke
				(width 0.1524)
				(type default)
			)
			(layer "F.SilkS")
		)
		(fp_poly
			(pts
				(xy -1.778 1.8796) (xy -1.778 -1.8796) (xy 1.778 -1.8796) (xy 1.778 1.8796)
			)
			(stroke
				(width 0)
				(type default)
			)
			(fill no)
			(layer "F.CrtYd")
		)
		(fp_poly
			(pts
				(xy -1.778 1.8796) (xy -1.778 -1.8796) (xy 1.778 -1.8796) (xy 1.778 1.8796)
			)
			(stroke
				(width 0)
				(type default)
			)
			(fill no)
			(layer "F.Fab")
		)
		(pad "B" smd custom
			(at -0.98425 0.9525 180)
			(size 0.1905 0.1905)
			(layers "F.Cu" "F.Mask" "F.Paste")
			(net "MB0_TEMP_C")
			(options
				(clearance outline)
				(anchor circle)
			)
			(primitives
				(gr_poly
					(pts
						(arc
							(start -0.1778 0.5715)
							(mid -0.321484 0.511984)
							(end -0.381 0.3683)
						)
						(arc
							(start -0.381 -0.3683)
							(mid -0.321484 -0.511984)
							(end -0.1778 -0.5715)
						)
						(arc
							(start 0.1778 -0.5715)
							(mid 0.321484 -0.511984)
							(end 0.381 -0.3683)
						)
						(arc
							(start 0.381 0.3683)
							(mid 0.321484 0.511984)
							(end 0.1778 0.5715)
						)
					)
					(width 0)
					(fill yes)
				)
			)
		)
		(pad "C" smd custom
			(at 0 -0.9525 180)
			(size 0.1905 0.1905)
			(layers "F.Cu" "F.Mask" "F.Paste")
			(net "MB0_TEMP_C")
			(options
				(clearance outline)
				(anchor circle)
			)
			(primitives
				(gr_poly
					(pts
						(arc
							(start -0.1778 0.5715)
							(mid -0.321484 0.511984)
							(end -0.381 0.3683)
						)
						(arc
							(start -0.381 -0.3683)
							(mid -0.321484 -0.511984)
							(end -0.1778 -0.5715)
						)
						(arc
							(start 0.1778 -0.5715)
							(mid 0.321484 -0.511984)
							(end 0.381 -0.3683)
						)
						(arc
							(start 0.381 0.3683)
							(mid 0.321484 0.511984)
							(end 0.1778 0.5715)
						)
					)
					(width 0)
					(fill yes)
				)
			)
		)
		(pad "E" smd custom
			(at 0.98425 0.9525 180)
			(size 0.1905 0.1905)
			(layers "F.Cu" "F.Mask" "F.Paste")
			(net "MB0_TEMP_E")
			(options
				(clearance outline)
				(anchor circle)
			)
			(primitives
				(gr_poly
					(pts
						(arc
							(start -0.1778 0.5715)
							(mid -0.321484 0.511984)
							(end -0.381 0.3683)
						)
						(arc
							(start -0.381 -0.3683)
							(mid -0.321484 -0.511984)
							(end -0.1778 -0.5715)
						)
						(arc
							(start 0.1778 -0.5715)
							(mid 0.321484 -0.511984)
							(end 0.381 -0.3683)
						)
						(arc
							(start 0.381 0.3683)
							(mid 0.321484 0.511984)
							(end 0.1778 0.5715)
						)
					)
					(width 0)
					(fill yes)
				)
			)
		)
	)
	(footprint ""
		(layer "F.Cu")
		(at 113.6142 -86.995)
		(property "Reference" "R455"
			(at 0 0 0)
			(layer "F.SilkS")
			(hide yes)
			(effects
				(font
					(size 1.27 1.27)
				)
			)
		)
		(property "Value" "4K7R2F-GP"
			(at 0.064008 -3.993896 0)
			(unlocked yes)
			(layer "F.Fab")
			(hide yes)
			(effects
				(font
					(size 1.016 1.016)
					(thickness 0.1524)
				)
			)
		)
		(property "Device Type" "R402H16"
			(at 0.064008 -5.517896 0)
			(unlocked yes)
			(layer "F.Fab")
			(hide yes)
			(effects
				(font
					(size 1.016 1.016)
					(thickness 0.1524)
				)
			)
		)
		(duplicate_pad_numbers_are_jumpers no)
		(fp_line
			(start -0.508 -0.9398)
			(end -0.508 0.9398)
			(stroke
				(width 0.1524)
				(type default)
			)
			(layer "F.SilkS")
		)
		(fp_line
			(start 0.508 -0.9398)
			(end -0.508 -0.9398)
			(stroke
				(width 0.1524)
				(type default)
			)
			(layer "F.SilkS")
		)
		(fp_rect
			(start -0.508 0.9398)
			(end 0.508 -0.9398)
			(stroke
				(width 0)
				(type default)
			)
			(fill no)
			(layer "F.CrtYd")
		)
		(fp_rect
			(start -0.508 0.9398)
			(end 0.508 -0.9398)
			(stroke
				(width 0)
				(type default)
			)
			(fill no)
			(layer "F.Fab")
		)
		(pad "1" smd custom
			(at 0 -0.4445)
			(size 0.1397 0.1397)
			(layers "F.Cu" "F.Mask" "F.Paste")
			(net "P1V8_E")
			(options
				(clearance outline)
				(anchor circle)
			)
			(primitives
				(gr_poly
					(pts
						(arc
							(start -0.1778 -0.2794)
							(mid -0.249642 -0.249642)
							(end -0.2794 -0.1778)
						)
						(arc
							(start -0.2794 0.1778)
							(mid -0.249642 0.249642)
							(end -0.1778 0.2794)
						)
						(arc
							(start 0.1778 0.2794)
							(mid 0.249642 0.249642)
							(end 0.2794 0.1778)
						)
						(arc
							(start 0.2794 -0.1778)
							(mid 0.249642 -0.249642)
							(end 0.1778 -0.2794)
						)
					)
					(width 0)
					(fill yes)
				)
			)
		)
		(pad "2" smd custom
			(at 0 0.4445)
			(size 0.1397 0.1397)
			(layers "F.Cu" "F.Mask" "F.Paste")
			(net "EXP_XM_ADDR_25")
			(options
				(clearance outline)
				(anchor circle)
			)
			(primitives
				(gr_poly
					(pts
						(arc
							(start -0.1778 -0.2794)
							(mid -0.249642 -0.249642)
							(end -0.2794 -0.1778)
						)
						(arc
							(start -0.2794 0.1778)
							(mid -0.249642 0.249642)
							(end -0.1778 0.2794)
						)
						(arc
							(start 0.1778 0.2794)
							(mid 0.249642 0.249642)
							(end 0.2794 0.1778)
						)
						(arc
							(start 0.2794 -0.1778)
							(mid 0.249642 -0.249642)
							(end 0.1778 -0.2794)
						)
					)
					(width 0)
					(fill yes)
				)
			)
		)
	)
	(footprint ""
		(layer "F.Cu")
		(at 58.9788 -95.9612 -90)
		(property "Reference" "C701"
			(at 0 0 270)
			(layer "F.SilkS")
			(hide yes)
			(effects
				(font
					(size 1.27 1.27)
				)
			)
		)
		(property "Value" "SC10U16V5KX-7-GP-U"
			(at -0.0762 -6.1214 270)
			(unlocked yes)
			(layer "F.Fab")
			(hide yes)
			(effects
				(font
					(size 1.016 1.016)
					(thickness 0.1524)
				)
			)
		)
		(property "Device Type" "C805H58"
			(at -0.0762 -8.1534 270)
			(unlocked yes)
			(layer "F.Fab")
			(hide yes)
			(effects
				(font
					(size 1.016 1.016)
					(thickness 0.1524)
				)
			)
		)
		(duplicate_pad_numbers_are_jumpers no)
		(fp_line
			(start 0.635 0)
			(end -0.635 0)
			(stroke
				(width 0.508)
				(type default)
			)
			(layer "F.SilkS")
		)
		(fp_rect
			(start -0.9652 1.778)
			(end 0.9652 -1.778)
			(stroke
				(width 0)
				(type default)
			)
			(fill no)
			(layer "F.CrtYd")
		)
		(fp_poly
			(pts
				(xy -0.9652 -1.778) (xy 0.9652 -1.778) (xy 0.9652 1.778) (xy -0.9652 1.778)
			)
			(stroke
				(width 0)
				(type default)
			)
			(fill no)
			(layer "F.Fab")
		)
		(pad "1" smd rect
			(at 0 -0.9652 270)
			(size 1.397 1.143)
			(layers "F.Cu" "F.Mask" "F.Paste")
			(net "P12V_STBY_VIN_U10")
		)
		(pad "2" smd rect
			(at 0 0.9652 270)
			(size 1.397 1.143)
			(layers "F.Cu" "F.Mask" "F.Paste")
			(net "GND")
		)
	)
	(footprint ""
		(layer "F.Cu")
		(at 13.895578 -44.590208 -90)
		(property "Reference" "C522"
			(at 0 0 270)
			(layer "F.SilkS")
			(hide yes)
			(effects
				(font
					(size 1.27 1.27)
				)
			)
		)
		(property "Value" "SCD015U25V2KX-GP"
			(at 1.1811 -2.7051 270)
			(unlocked yes)
			(layer "F.Fab")
			(hide yes)
			(effects
				(font
					(size 1.016 1.016)
					(thickness 0.1524)
				)
			)
		)
		(property "Device Type" "C402H22"
			(at 1.1811 -4.2291 270)
			(unlocked yes)
			(layer "F.Fab")
			(hide yes)
			(effects
				(font
					(size 1.016 1.016)
					(thickness 0.1524)
				)
			)
		)
		(duplicate_pad_numbers_are_jumpers no)
		(fp_rect
			(start -0.4318 0.9525)
			(end 0.4318 -0.9525)
			(stroke
				(width 0)
				(type default)
			)
			(fill no)
			(layer "F.CrtYd")
		)
		(fp_rect
			(start -0.4318 0.9525)
			(end 0.4318 -0.9525)
			(stroke
				(width 0)
				(type default)
			)
			(fill no)
			(layer "F.Fab")
		)
		(pad "1" smd custom
			(at 0 -0.4445 270)
			(size 0.1524 0.1524)
			(layers "F.Cu" "F.Mask" "F.Paste")
			(net "MB0_CM_SENSE_P")
			(options
				(clearance outline)
				(anchor circle)
			)
			(primitives
				(gr_poly
					(pts
						(arc
							(start 0.3048 -0.2032)
							(mid 0.275042 -0.275042)
							(end 0.2032 -0.3048)
						)
						(arc
							(start -0.2032 -0.3048)
							(mid -0.275042 -0.275042)
							(end -0.3048 -0.2032)
						)
						(arc
							(start -0.3048 0.2032)
							(mid -0.275042 0.275042)
							(end -0.2032 0.3048)
						)
						(arc
							(start 0.2032 0.3048)
							(mid 0.275042 0.275042)
							(end 0.3048 0.2032)
						)
					)
					(width 0)
					(fill yes)
				)
			)
		)
		(pad "2" smd custom
			(at 0 0.4445 270)
			(size 0.1524 0.1524)
			(layers "F.Cu" "F.Mask" "F.Paste")
			(net "MB0_CM_SENSE_N")
			(options
				(clearance outline)
				(anchor circle)
			)
			(primitives
				(gr_poly
					(pts
						(arc
							(start 0.3048 -0.2032)
							(mid 0.275042 -0.275042)
							(end 0.2032 -0.3048)
						)
						(arc
							(start -0.2032 -0.3048)
							(mid -0.275042 -0.275042)
							(end -0.3048 -0.2032)
						)
						(arc
							(start -0.3048 0.2032)
							(mid -0.275042 0.275042)
							(end -0.2032 0.3048)
						)
						(arc
							(start 0.2032 0.3048)
							(mid 0.275042 0.275042)
							(end 0.3048 0.2032)
						)
					)
					(width 0)
					(fill yes)
				)
			)
		)
	)
	(footprint ""
		(layer "F.Cu")
		(at 165.172898 -58.108596)
		(property "Reference" "R262"
			(at 0 0 0)
			(layer "F.SilkS")
			(hide yes)
			(effects
				(font
					(size 1.27 1.27)
				)
			)
		)
		(property "Value" "4K7R2F-GP"
			(at 0.064008 -3.993896 0)
			(unlocked yes)
			(layer "F.Fab")
			(hide yes)
			(effects
				(font
					(size 1.016 1.016)
					(thickness 0.1524)
				)
			)
		)
		(property "Device Type" "R402H16"
			(at 0.064008 -5.517896 0)
			(unlocked yes)
			(layer "F.Fab")
			(hide yes)
			(effects
				(font
					(size 1.016 1.016)
					(thickness 0.1524)
				)
			)
		)
		(duplicate_pad_numbers_are_jumpers no)
		(fp_line
			(start -0.508 -0.9398)
			(end -0.508 0.9398)
			(stroke
				(width 0.1524)
				(type default)
			)
			(layer "F.SilkS")
		)
		(fp_line
			(start 0.508 -0.9398)
			(end -0.508 -0.9398)
			(stroke
				(width 0.1524)
				(type default)
			)
			(layer "F.SilkS")
		)
		(fp_rect
			(start -0.508 0.9398)
			(end 0.508 -0.9398)
			(stroke
				(width 0)
				(type default)
			)
			(fill no)
			(layer "F.CrtYd")
		)
		(fp_rect
			(start -0.508 0.9398)
			(end 0.508 -0.9398)
			(stroke
				(width 0)
				(type default)
			)
			(fill no)
			(layer "F.Fab")
		)
		(pad "1" smd custom
			(at 0 -0.4445)
			(size 0.1397 0.1397)
			(layers "F.Cu" "F.Mask" "F.Paste")
			(net "P1V8_C")
			(options
				(clearance outline)
				(anchor circle)
			)
			(primitives
				(gr_poly
					(pts
						(arc
							(start -0.1778 -0.2794)
							(mid -0.249642 -0.249642)
							(end -0.2794 -0.1778)
						)
						(arc
							(start -0.2794 0.1778)
							(mid -0.249642 0.249642)
							(end -0.1778 0.2794)
						)
						(arc
							(start 0.1778 0.2794)
							(mid 0.249642 0.249642)
							(end 0.2794 0.1778)
						)
						(arc
							(start 0.2794 -0.1778)
							(mid 0.249642 -0.249642)
							(end 0.1778 -0.2794)
						)
					)
					(width 0)
					(fill yes)
				)
			)
		)
		(pad "2" smd custom
			(at 0 0.4445)
			(size 0.1397 0.1397)
			(layers "F.Cu" "F.Mask" "F.Paste")
			(net "ICE1_TMS")
			(options
				(clearance outline)
				(anchor circle)
			)
			(primitives
				(gr_poly
					(pts
						(arc
							(start -0.1778 -0.2794)
							(mid -0.249642 -0.249642)
							(end -0.2794 -0.1778)
						)
						(arc
							(start -0.2794 0.1778)
							(mid -0.249642 0.249642)
							(end -0.1778 0.2794)
						)
						(arc
							(start 0.1778 0.2794)
							(mid 0.249642 0.249642)
							(end 0.2794 0.1778)
						)
						(arc
							(start 0.2794 -0.1778)
							(mid 0.249642 -0.249642)
							(end 0.1778 -0.2794)
						)
					)
					(width 0)
					(fill yes)
				)
			)
		)
	)
	(footprint ""
		(layer "F.Cu")
		(at 18.6944 -80.8228 90)
		(property "Reference" "C528"
			(at 0 0 90)
			(layer "F.SilkS")
			(hide yes)
			(effects
				(font
					(size 1.27 1.27)
				)
			)
		)
		(property "Value" "SCD1U16V2KX-3GP"
			(at 1.1811 -2.7051 90)
			(unlocked yes)
			(layer "F.Fab")
			(hide yes)
			(effects
				(font
					(size 1.016 1.016)
					(thickness 0.1524)
				)
			)
		)
		(property "Device Type" "C402H22"
			(at 1.1811 -4.2291 90)
			(unlocked yes)
			(layer "F.Fab")
			(hide yes)
			(effects
				(font
					(size 1.016 1.016)
					(thickness 0.1524)
				)
			)
		)
		(duplicate_pad_numbers_are_jumpers no)
		(fp_rect
			(start -0.4318 0.9525)
			(end 0.4318 -0.9525)
			(stroke
				(width 0)
				(type default)
			)
			(fill no)
			(layer "F.CrtYd")
		)
		(fp_rect
			(start -0.4318 0.9525)
			(end 0.4318 -0.9525)
			(stroke
				(width 0)
				(type default)
			)
			(fill no)
			(layer "F.Fab")
		)
		(pad "1" smd custom
			(at 0 -0.4445 90)
			(size 0.1524 0.1524)
			(layers "F.Cu" "F.Mask" "F.Paste")
			(net "P3V3")
			(options
				(clearance outline)
				(anchor circle)
			)
			(primitives
				(gr_poly
					(pts
						(arc
							(start 0.3048 -0.2032)
							(mid 0.275042 -0.275042)
							(end 0.2032 -0.3048)
						)
						(arc
							(start -0.2032 -0.3048)
							(mid -0.275042 -0.275042)
							(end -0.3048 -0.2032)
						)
						(arc
							(start -0.3048 0.2032)
							(mid -0.275042 0.275042)
							(end -0.2032 0.3048)
						)
						(arc
							(start 0.2032 0.3048)
							(mid 0.275042 0.275042)
							(end 0.3048 0.2032)
						)
					)
					(width 0)
					(fill yes)
				)
			)
		)
		(pad "2" smd custom
			(at 0 0.4445 90)
			(size 0.1524 0.1524)
			(layers "F.Cu" "F.Mask" "F.Paste")
			(net "GND")
			(options
				(clearance outline)
				(anchor circle)
			)
			(primitives
				(gr_poly
					(pts
						(arc
							(start 0.3048 -0.2032)
							(mid 0.275042 -0.275042)
							(end 0.2032 -0.3048)
						)
						(arc
							(start -0.2032 -0.3048)
							(mid -0.275042 -0.275042)
							(end -0.3048 -0.2032)
						)
						(arc
							(start -0.3048 0.2032)
							(mid -0.275042 0.275042)
							(end -0.2032 0.3048)
						)
						(arc
							(start 0.2032 0.3048)
							(mid 0.275042 0.275042)
							(end 0.3048 0.2032)
						)
					)
					(width 0)
					(fill yes)
				)
			)
		)
	)
)
